(kicad_pcb
	(version 20260206)
	(generator "pcbnew")
	(generator_version "10.0")
	(general
		(thickness 1.6)
		(legacy_teardrops no)
	)
	(paper "A4")
	(title_block
		(title "01162023_DA0F0TEBIF0_F0T_Expander_BD_F_brd_V02_OCP.brd")
		(comment 1 "Grand Teton / footprints 4309-4315 of 9728")
	)
	(layers
		(0 "F.Cu" signal "TOP")
		(4 "In1.Cu" signal "GND")
		(6 "In2.Cu" signal "VCC")
		(8 "In3.Cu" signal "VCC1")
		(10 "In4.Cu" signal "GND1")
		(12 "In5.Cu" signal "IN1")
		(14 "In6.Cu" signal "GND2")
		(16 "In7.Cu" signal "IN2")
		(18 "In8.Cu" signal "GND3")
		(20 "In9.Cu" signal "IN3")
		(22 "In10.Cu" signal "GND4")
		(24 "In11.Cu" signal "IN4")
		(26 "In12.Cu" signal "GND5")
		(28 "In13.Cu" signal "IN5")
		(30 "In14.Cu" signal "GND6")
		(32 "In15.Cu" signal "IN6")
		(34 "In16.Cu" signal "GND7")
		(2 "B.Cu" signal "BOTTOM")
		(9 "F.Adhes" user "F.Adhesive")
		(11 "B.Adhes" user "B.Adhesive")
		(13 "F.Paste" user "Package Geometry/Pastemask Top")
		(15 "B.Paste" user "Package Geometry/Pastemask Bottom")
		(5 "F.SilkS" user "Ref Des/Silkscreen Top")
		(7 "B.SilkS" user "Ref Des/Silkscreen Bottom")
		(1 "F.Mask" user "Board Geometry/Soldermask Top")
		(3 "B.Mask" user "Board Geometry/Soldermask Bottom")
		(17 "Dwgs.User" user "User.Drawings")
		(19 "Cmts.User" user "User.Comments")
		(21 "Eco1.User" user "User.Eco1")
		(23 "Eco2.User" user "User.Eco2")
		(25 "Edge.Cuts" user "Board Geometry/Outline")
		(27 "Margin" user)
		(31 "F.CrtYd" user "Package Geometry/Place Bound Top")
		(29 "B.CrtYd" user "Package Geometry/Place Bound Bottom")
		(35 "F.Fab" user "Ref Des/Assembly Top")
		(33 "B.Fab" user "Ref Des/Assembly Bottom")
	)
	(footprint ""
		(layer "F.Cu")
		(at 214.310976 -370.321586 180)
		(property "Reference" "PC15"
			(at 0 0 180)
			(layer "F.SilkS")
			(hide yes)
			(effects
				(font
					(size 1.27 1.27)
				)
			)
		)
		(property "Value" ""
			(at 0 0 180)
			(layer "F.Fab")
			(effects
				(font
					(size 1.27 1.27)
				)
			)
		)
		(duplicate_pad_numbers_are_jumpers no)
		(fp_line
			(start 0.7874 0.4064)
			(end -0.7874 0.4064)
			(stroke
				(width 0.1524)
				(type default)
			)
			(layer "F.SilkS")
		)
		(fp_line
			(start 0.7874 -0.4064)
			(end 0.7874 0.4064)
			(stroke
				(width 0.1524)
				(type default)
			)
			(layer "F.SilkS")
		)
		(fp_line
			(start -0.7874 0.4064)
			(end -0.7874 -0.4064)
			(stroke
				(width 0.1524)
				(type default)
			)
			(layer "F.SilkS")
		)
		(fp_line
			(start -0.7874 -0.4064)
			(end 0.7874 -0.4064)
			(stroke
				(width 0.1524)
				(type default)
			)
			(layer "F.SilkS")
		)
		(fp_line
			(start 0.67945 0.3048)
			(end 0.120396 0.3048)
			(stroke
				(width 0.1)
				(type default)
			)
			(layer "F.Fab")
		)
		(fp_line
			(start 0.67945 -0.3048)
			(end 0.67945 0.3048)
			(stroke
				(width 0.1)
				(type default)
			)
			(layer "F.Fab")
		)
		(fp_line
			(start 0.12065 -0.2794)
			(end 0.12065 -0.3048)
			(stroke
				(width 0.1)
				(type default)
			)
			(layer "F.Fab")
		)
		(fp_line
			(start 0.12065 -0.3048)
			(end 0.67945 -0.3048)
			(stroke
				(width 0.1)
				(type default)
			)
			(layer "F.Fab")
		)
		(fp_line
			(start 0.120396 0.3048)
			(end 0.120396 0.2794)
			(stroke
				(width 0.1)
				(type default)
			)
			(layer "F.Fab")
		)
		(fp_line
			(start 0.120396 0.2794)
			(end -0.12065 0.2794)
			(stroke
				(width 0.1)
				(type default)
			)
			(layer "F.Fab")
		)
		(fp_line
			(start -0.12065 0.3048)
			(end -0.67945 0.3048)
			(stroke
				(width 0.1)
				(type default)
			)
			(layer "F.Fab")
		)
		(fp_line
			(start -0.12065 0.2794)
			(end -0.12065 0.3048)
			(stroke
				(width 0.1)
				(type default)
			)
			(layer "F.Fab")
		)
		(fp_line
			(start -0.12065 -0.2794)
			(end 0.12065 -0.2794)
			(stroke
				(width 0.1)
				(type default)
			)
			(layer "F.Fab")
		)
		(fp_line
			(start -0.12065 -0.305054)
			(end -0.12065 -0.2794)
			(stroke
				(width 0.1)
				(type default)
			)
			(layer "F.Fab")
		)
		(fp_line
			(start -0.67945 0.3048)
			(end -0.67945 -0.305054)
			(stroke
				(width 0.1)
				(type default)
			)
			(layer "F.Fab")
		)
		(fp_line
			(start -0.67945 -0.305054)
			(end -0.12065 -0.305054)
			(stroke
				(width 0.1)
				(type default)
			)
			(layer "F.Fab")
		)
		(pad "1" smd circle
			(at -0.40005 0 180)
			(size 0 0)
			(layers "F.Cu" "F.Mask" "F.Paste")
			(net "HSC_SS")
		)
		(pad "2" smd circle
			(at 0.40005 0 180)
			(size 0 0)
			(layers "F.Cu" "F.Mask" "F.Paste")
			(net "AGND_HSC")
		)
	)
	(footprint ""
		(layer "F.Cu")
		(at 424.814492 -356.244906 90)
		(property "Reference" "C2455"
			(at 0 0 90)
			(layer "F.SilkS")
			(hide yes)
			(effects
				(font
					(size 1.27 1.27)
				)
			)
		)
		(property "Value" ""
			(at 0 0 90)
			(layer "F.Fab")
			(effects
				(font
					(size 1.27 1.27)
				)
			)
		)
		(duplicate_pad_numbers_are_jumpers no)
		(fp_line
			(start 0.299974 -0.150114)
			(end 0.299974 0.150114)
			(stroke
				(width 0.1)
				(type default)
			)
			(layer "F.Fab")
		)
		(fp_line
			(start -0.299974 -0.150114)
			(end 0.299974 -0.150114)
			(stroke
				(width 0.1)
				(type default)
			)
			(layer "F.Fab")
		)
		(fp_line
			(start 0.299974 0.150114)
			(end -0.299974 0.150114)
			(stroke
				(width 0.1)
				(type default)
			)
			(layer "F.Fab")
		)
		(fp_line
			(start -0.299974 0.150114)
			(end -0.299974 -0.150114)
			(stroke
				(width 0.1)
				(type default)
			)
			(layer "F.Fab")
		)
		(pad "1" smd rect
			(at -0.2667 0 90)
			(size 0.3048 0.381)
			(layers "F.Cu" "F.Mask" "F.Paste")
			(net "P5E_PEX3_STN4_TX_DP<71>")
		)
		(pad "2" smd rect
			(at 0.2667 0 90)
			(size 0.3048 0.381)
			(layers "F.Cu" "F.Mask" "F.Paste")
			(net "P5E_PEX3_STN4_TX_C_DP<71>")
		)
	)
	(footprint ""
		(layer "F.Cu")
		(at 193.065908 -360.074718)
		(property "Reference" "J58"
			(at -1.127252 -4.983988 0)
			(unlocked yes)
			(layer "F.SilkS")
			(effects
				(font
					(size 0.7874 0.5842)
					(thickness 0.1524)
				)
				(justify left)
			)
		)
		(property "Value" ""
			(at 0 0 0)
			(layer "F.Fab")
			(effects
				(font
					(size 1.27 1.27)
				)
			)
		)
		(duplicate_pad_numbers_are_jumpers no)
		(fp_line
			(start -1.27 -3.81)
			(end 1.27 -3.81)
			(stroke
				(width 0.1524)
				(type default)
			)
			(layer "F.SilkS")
		)
		(fp_line
			(start -1.27 -0.7747)
			(end -1.27 -3.81)
			(stroke
				(width 0.1524)
				(type default)
			)
			(layer "F.SilkS")
		)
		(fp_line
			(start -1.27 3.81)
			(end -1.27 0.7747)
			(stroke
				(width 0.1524)
				(type default)
			)
			(layer "F.SilkS")
		)
		(fp_line
			(start 1.27 -3.81)
			(end 1.27 -3.3147)
			(stroke
				(width 0.1524)
				(type default)
			)
			(layer "F.SilkS")
		)
		(fp_line
			(start 1.27 -1.7653)
			(end 1.27 1.7653)
			(stroke
				(width 0.1524)
				(type default)
			)
			(layer "F.SilkS")
		)
		(fp_line
			(start 1.27 3.3147)
			(end 1.27 3.81)
			(stroke
				(width 0.1524)
				(type default)
			)
			(layer "F.SilkS")
		)
		(fp_line
			(start 1.27 3.81)
			(end -1.27 3.81)
			(stroke
				(width 0.1524)
				(type default)
			)
			(layer "F.SilkS")
		)
		(fp_poly
			(pts
				(xy 4.3942 -3.048) (xy 4.3942 -2.032) (xy 3.3782 -2.54)
			)
			(stroke
				(width 0)
				(type default)
			)
			(fill yes)
			(layer "F.SilkS")
		)
		(fp_line
			(start -1.27 -3.81)
			(end -1.27 3.81)
			(stroke
				(width 0.1)
				(type default)
			)
			(layer "F.Fab")
		)
		(fp_line
			(start -1.27 3.81)
			(end 1.27 3.81)
			(stroke
				(width 0.1)
				(type default)
			)
			(layer "F.Fab")
		)
		(fp_line
			(start 1.27 -3.81)
			(end -1.27 -3.81)
			(stroke
				(width 0.1)
				(type default)
			)
			(layer "F.Fab")
		)
		(fp_line
			(start 1.27 3.81)
			(end 1.27 -3.81)
			(stroke
				(width 0.1)
				(type default)
			)
			(layer "F.Fab")
		)
		(fp_poly
			(pts
				(xy 4.3942 -3.048) (xy 4.3942 -2.032) (xy 3.3782 -2.54)
			)
			(stroke
				(width 0)
				(type default)
			)
			(fill yes)
			(layer "F.Fab")
		)
		(fp_text user "3"
			(at 3.720846 2.239518 0)
			(unlocked yes)
			(layer "F.SilkS")
			(effects
				(font
					(size 0.7874 0.5842)
					(thickness 0.1524)
				)
			)
		)
		(fp_text user "3"
			(at 3.921252 2.54 90)
			(unlocked yes)
			(layer "F.Fab")
			(effects
				(font
					(size 0.7874 0.5842)
					(thickness 0.1524)
				)
			)
		)
		(pad "1" smd rect
			(at 1.459992 -2.54 90)
			(size 1.27 3.429)
			(layers "F.Cu" "F.Mask" "F.Paste")
			(net "Net_616")
		)
		(pad "2" smd rect
			(at -1.459992 0 90)
			(size 1.27 3.429)
			(layers "F.Cu" "F.Mask" "F.Paste")
			(net "MB_HSC_ISO_D1_EN")
		)
		(pad "3" smd rect
			(at 1.459992 2.54 90)
			(size 1.27 3.429)
			(layers "F.Cu" "F.Mask" "F.Paste")
			(net "PD_MB_HSC_ISO_D1_EN")
		)
	)
	(footprint ""
		(layer "F.Cu")
		(at 136.54659 -58.323734)
		(property "Reference" "PC317"
			(at 0 0 0)
			(layer "F.SilkS")
			(hide yes)
			(effects
				(font
					(size 1.27 1.27)
				)
			)
		)
		(property "Value" ""
			(at 0 0 0)
			(layer "F.Fab")
			(effects
				(font
					(size 1.27 1.27)
				)
			)
		)
		(duplicate_pad_numbers_are_jumpers no)
		(fp_line
			(start -1.524 -0.762)
			(end 1.524 -0.762)
			(stroke
				(width 0.1524)
				(type default)
			)
			(layer "F.SilkS")
		)
		(fp_line
			(start -1.524 0.762)
			(end -1.524 -0.762)
			(stroke
				(width 0.1524)
				(type default)
			)
			(layer "F.SilkS")
		)
		(fp_line
			(start 1.524 -0.762)
			(end 1.524 0.762)
			(stroke
				(width 0.1524)
				(type default)
			)
			(layer "F.SilkS")
		)
		(fp_line
			(start 1.524 0.762)
			(end -1.524 0.762)
			(stroke
				(width 0.1524)
				(type default)
			)
			(layer "F.SilkS")
		)
		(fp_line
			(start -1.1049 -0.724916)
			(end -1.1049 0.724916)
			(stroke
				(width 0.1)
				(type default)
			)
			(layer "F.Fab")
		)
		(fp_line
			(start -1.1049 0.724916)
			(end 1.1049 0.724916)
			(stroke
				(width 0.1)
				(type default)
			)
			(layer "F.Fab")
		)
		(fp_line
			(start 1.1049 -0.724916)
			(end -1.1049 -0.724916)
			(stroke
				(width 0.1)
				(type default)
			)
			(layer "F.Fab")
		)
		(fp_line
			(start 1.1049 0.724916)
			(end 1.1049 -0.724916)
			(stroke
				(width 0.1)
				(type default)
			)
			(layer "F.Fab")
		)
		(pad "1" smd rect
			(at -0.889 0 180)
			(size 1.016 1.27)
			(layers "F.Cu" "F.Mask" "F.Paste")
			(net "GND")
		)
		(pad "2" smd rect
			(at 0.889 0 180)
			(size 1.016 1.27)
			(layers "F.Cu" "F.Mask" "F.Paste")
			(net "P12V_AUX")
		)
	)
	(footprint ""
		(layer "F.Cu")
		(at 262.312404 -342.4428 180)
		(property "Reference" "U436"
			(at -3.322066 -1.352296 0)
			(unlocked yes)
			(layer "F.SilkS")
			(effects
				(font
					(size 0.7874 0.5842)
					(thickness 0.1524)
				)
				(justify left)
			)
		)
		(property "Value" ""
			(at 0 0 180)
			(layer "F.Fab")
			(effects
				(font
					(size 1.27 1.27)
				)
			)
		)
		(duplicate_pad_numbers_are_jumpers no)
		(fp_line
			(start 2.046478 1.450086)
			(end 2.046478 -1.450086)
			(stroke
				(width 0.1524)
				(type default)
			)
			(layer "F.SilkS")
		)
		(fp_line
			(start 2.046478 -1.450086)
			(end 0.484886 -1.450086)
			(stroke
				(width 0.1524)
				(type default)
			)
			(layer "F.SilkS")
		)
		(fp_line
			(start 0.484886 -1.450086)
			(end 0 -0.762)
			(stroke
				(width 0.1524)
				(type default)
			)
			(layer "F.SilkS")
		)
		(fp_line
			(start 0 -0.762)
			(end -0.484886 -1.450086)
			(stroke
				(width 0.1524)
				(type default)
			)
			(layer "F.SilkS")
		)
		(fp_line
			(start -0.484886 -1.450086)
			(end -2.046478 -1.450086)
			(stroke
				(width 0.1524)
				(type default)
			)
			(layer "F.SilkS")
		)
		(fp_line
			(start -2.046478 1.450086)
			(end 2.046478 1.450086)
			(stroke
				(width 0.1524)
				(type default)
			)
			(layer "F.SilkS")
		)
		(fp_line
			(start -2.046478 -1.450086)
			(end -2.046478 1.450086)
			(stroke
				(width 0.1524)
				(type default)
			)
			(layer "F.SilkS")
		)
		(fp_poly
			(pts
				(xy -3.2512 -0.44196) (xy -3.2512 -1.45796) (xy -2.2352 -0.94996)
			)
			(stroke
				(width 0)
				(type default)
			)
			(fill yes)
			(layer "F.SilkS")
		)
		(fp_line
			(start 0.87503 1.450086)
			(end 0.87503 -1.450086)
			(stroke
				(width 0.1)
				(type default)
			)
			(layer "F.Fab")
		)
		(fp_line
			(start 0.87503 -1.450086)
			(end -0.87503 -1.450086)
			(stroke
				(width 0.1)
				(type default)
			)
			(layer "F.Fab")
		)
		(fp_line
			(start -0.87503 1.450086)
			(end 0.87503 1.450086)
			(stroke
				(width 0.1)
				(type default)
			)
			(layer "F.Fab")
		)
		(fp_line
			(start -0.87503 -1.450086)
			(end -0.87503 1.450086)
			(stroke
				(width 0.1)
				(type default)
			)
			(layer "F.Fab")
		)
		(fp_poly
			(pts
				(xy -3.2512 -0.44196) (xy -3.2512 -1.45796) (xy -2.2352 -0.94996)
			)
			(stroke
				(width 0)
				(type default)
			)
			(fill yes)
			(layer "F.Fab")
		)
		(pad "1" smd rect
			(at -1.309878 -0.94996 270)
			(size 0.635 1.2192)
			(layers "F.Cu" "F.Mask" "F.Paste")
			(net "A_HSC_LOW_GATE")
		)
		(pad "2" smd rect
			(at -1.309878 0 270)
			(size 0.635 1.2192)
			(layers "F.Cu" "F.Mask" "F.Paste")
			(net "GND")
		)
		(pad "3" smd rect
			(at -1.309878 0.94996 270)
			(size 0.635 1.2192)
			(layers "F.Cu" "F.Mask" "F.Paste")
			(net "A_HSC_LOW")
		)
		(pad "4" smd rect
			(at 1.309878 0.94996 270)
			(size 0.635 1.2192)
			(layers "F.Cu" "F.Mask" "F.Paste")
			(net "A_HSC_HIGH")
		)
		(pad "5" smd rect
			(at 1.309878 0 270)
			(size 0.635 1.2192)
			(layers "F.Cu" "F.Mask" "F.Paste")
			(net "HSC_OC_LT6700_VS")
		)
		(pad "6" smd rect
			(at 1.309878 -0.94996 270)
			(size 0.635 1.2192)
			(layers "F.Cu" "F.Mask" "F.Paste")
			(net "HSC_D_OC_R")
		)
	)
	(footprint ""
		(layer "F.Cu")
		(at 102.229412 -385.205224)
		(property "Reference" "R6294"
			(at 0 0 0)
			(layer "F.SilkS")
			(hide yes)
			(effects
				(font
					(size 1.27 1.27)
				)
			)
		)
		(property "Value" ""
			(at 0 0 0)
			(layer "F.Fab")
			(effects
				(font
					(size 1.27 1.27)
				)
			)
		)
		(duplicate_pad_numbers_are_jumpers no)
		(fp_line
			(start -0.7874 -0.4064)
			(end 0.7874 -0.4064)
			(stroke
				(width 0.1524)
				(type default)
			)
			(layer "F.SilkS")
		)
		(fp_line
			(start 0.7874 -0.4064)
			(end 0.7874 0.4064)
			(stroke
				(width 0.1524)
				(type default)
			)
			(layer "F.SilkS")
		)
		(fp_line
			(start 0.7874 0.4064)
			(end -0.7874 0.4064)
			(stroke
				(width 0.1524)
				(type default)
			)
			(layer "F.SilkS")
		)
		(fp_line
			(start -0.67945 -0.305054)
			(end -0.12065 -0.305054)
			(stroke
				(width 0.1)
				(type default)
			)
			(layer "F.Fab")
		)
		(fp_line
			(start -0.67945 0.3048)
			(end -0.67945 -0.305054)
			(stroke
				(width 0.1)
				(type default)
			)
			(layer "F.Fab")
		)
		(fp_line
			(start -0.12065 -0.305054)
			(end -0.12065 -0.2794)
			(stroke
				(width 0.1)
				(type default)
			)
			(layer "F.Fab")
		)
		(fp_line
			(start -0.12065 -0.2794)
			(end 0.12065 -0.2794)
			(stroke
				(width 0.1)
				(type default)
			)
			(layer "F.Fab")
		)
		(fp_line
			(start -0.12065 0.2794)
			(end -0.12065 0.3048)
			(stroke
				(width 0.1)
				(type default)
			)
			(layer "F.Fab")
		)
		(fp_line
			(start -0.12065 0.3048)
			(end -0.67945 0.3048)
			(stroke
				(width 0.1)
				(type default)
			)
			(layer "F.Fab")
		)
		(fp_line
			(start 0.120396 0.2794)
			(end -0.12065 0.2794)
			(stroke
				(width 0.1)
				(type default)
			)
			(layer "F.Fab")
		)
		(fp_line
			(start 0.120396 0.3048)
			(end 0.120396 0.2794)
			(stroke
				(width 0.1)
				(type default)
			)
			(layer "F.Fab")
		)
		(fp_line
			(start 0.12065 -0.3048)
			(end 0.67945 -0.3048)
			(stroke
				(width 0.1)
				(type default)
			)
			(layer "F.Fab")
		)
		(fp_line
			(start 0.12065 -0.2794)
			(end 0.12065 -0.3048)
			(stroke
				(width 0.1)
				(type default)
			)
			(layer "F.Fab")
		)
		(fp_line
			(start 0.67945 -0.3048)
			(end 0.67945 0.3048)
			(stroke
				(width 0.1)
				(type default)
			)
			(layer "F.Fab")
		)
		(fp_line
			(start 0.67945 0.3048)
			(end 0.120396 0.3048)
			(stroke
				(width 0.1)
				(type default)
			)
			(layer "F.Fab")
		)
		(pad "1" smd rect
			(at -0.40005 0 180)
			(size 0.4572 0.508)
			(layers "F.Cu" "F.Mask" "F.Paste")
			(net "USB2_MB_BMC_DP")
		)
		(pad "2" smd rect
			(at 0.40005 0 180)
			(size 0.4572 0.508)
			(layers "F.Cu" "F.Mask" "F.Paste")
			(net "GND")
		)
	)
	(footprint ""
		(layer "F.Cu")
		(at 128.48336 -160.327848 180)
		(property "Reference" "PR6895"
			(at 0 0 180)
			(layer "F.SilkS")
			(hide yes)
			(effects
				(font
					(size 1.27 1.27)
				)
			)
		)
		(property "Value" ""
			(at 0 0 180)
			(layer "F.Fab")
			(effects
				(font
					(size 1.27 1.27)
				)
			)
		)
		(duplicate_pad_numbers_are_jumpers no)
		(fp_line
			(start 0.7874 0.4064)
			(end -0.7874 0.4064)
			(stroke
				(width 0.1524)
				(type default)
			)
			(layer "F.SilkS")
		)
		(fp_line
			(start 0.7874 -0.4064)
			(end 0.7874 0.4064)
			(stroke
				(width 0.1524)
				(type default)
			)
			(layer "F.SilkS")
		)
		(fp_line
			(start -0.7874 0.4064)
			(end -0.7874 -0.4064)
			(stroke
				(width 0.1524)
				(type default)
			)
			(layer "F.SilkS")
		)
		(fp_line
			(start -0.7874 -0.4064)
			(end 0.7874 -0.4064)
			(stroke
				(width 0.1524)
				(type default)
			)
			(layer "F.SilkS")
		)
		(fp_line
			(start 0.67945 0.3048)
			(end 0.120396 0.3048)
			(stroke
				(width 0.1)
				(type default)
			)
			(layer "F.Fab")
		)
		(fp_line
			(start 0.67945 -0.3048)
			(end 0.67945 0.3048)
			(stroke
				(width 0.1)
				(type default)
			)
			(layer "F.Fab")
		)
		(fp_line
			(start 0.12065 -0.2794)
			(end 0.12065 -0.3048)
			(stroke
				(width 0.1)
				(type default)
			)
			(layer "F.Fab")
		)
		(fp_line
			(start 0.12065 -0.3048)
			(end 0.67945 -0.3048)
			(stroke
				(width 0.1)
				(type default)
			)
			(layer "F.Fab")
		)
		(fp_line
			(start 0.120396 0.3048)
			(end 0.120396 0.2794)
			(stroke
				(width 0.1)
				(type default)
			)
			(layer "F.Fab")
		)
		(fp_line
			(start 0.120396 0.2794)
			(end -0.12065 0.2794)
			(stroke
				(width 0.1)
				(type default)
			)
			(layer "F.Fab")
		)
		(fp_line
			(start -0.12065 0.3048)
			(end -0.67945 0.3048)
			(stroke
				(width 0.1)
				(type default)
			)
			(layer "F.Fab")
		)
		(fp_line
			(start -0.12065 0.2794)
			(end -0.12065 0.3048)
			(stroke
				(width 0.1)
				(type default)
			)
			(layer "F.Fab")
		)
		(fp_line
			(start -0.12065 -0.2794)
			(end 0.12065 -0.2794)
			(stroke
				(width 0.1)
				(type default)
			)
			(layer "F.Fab")
		)
		(fp_line
			(start -0.12065 -0.305054)
			(end -0.12065 -0.2794)
			(stroke
				(width 0.1)
				(type default)
			)
			(layer "F.Fab")
		)
		(fp_line
			(start -0.67945 0.3048)
			(end -0.67945 -0.305054)
			(stroke
				(width 0.1)
				(type default)
			)
			(layer "F.Fab")
		)
		(fp_line
			(start -0.67945 -0.305054)
			(end -0.12065 -0.305054)
			(stroke
				(width 0.1)
				(type default)
			)
			(layer "F.Fab")
		)
		(pad "1" smd circle
			(at -0.40005 0 180)
			(size 0 0)
			(layers "F.Cu" "F.Mask" "F.Paste")
			(net "P12V_NIC2_CO_ISET")
		)
		(pad "2" smd circle
			(at 0.40005 0 180)
			(size 0 0)
			(layers "F.Cu" "F.Mask" "F.Paste")
			(net "P12V_NIC2_CO_ISET_R")
		)
	)
)
